(kicad_pcb
	(version 20241229)
	(generator "pcbnew")
	(generator_version "9.0")
	(general
		(thickness 1.294)
		(legacy_teardrops no)
	)
	(paper "A3")
	(title_block
		(title "Kintex 410T devboard")
		(date "2024-04-03")
		(rev "1.1.2")
		(comment 9 "footprints 403-407 of 975")
	)
	(layers
		(0 "F.Cu" mixed)
		(4 "In1.Cu" power)
		(6 "In2.Cu" power)
		(8 "In3.Cu" mixed)
		(10 "In4.Cu" power)
		(12 "In5.Cu" mixed)
		(14 "In6.Cu" power)
		(16 "In7.Cu" mixed)
		(18 "In8.Cu" power)
		(2 "B.Cu" mixed)
		(9 "F.Adhes" user "F.Adhesive")
		(11 "B.Adhes" user "B.Adhesive")
		(13 "F.Paste" user)
		(15 "B.Paste" user)
		(5 "F.SilkS" user "F.Silkscreen")
		(7 "B.SilkS" user "B.Silkscreen")
		(1 "F.Mask" user)
		(3 "B.Mask" user)
		(17 "Dwgs.User" user "User.Drawings")
		(19 "Cmts.User" user "User.Comments")
		(21 "Eco1.User" user "User.Eco1")
		(23 "Eco2.User" user "User.Eco2")
		(25 "Edge.Cuts" user)
		(27 "Margin" user)
		(31 "F.CrtYd" user "F.Courtyard")
		(29 "B.CrtYd" user "B.Courtyard")
		(35 "F.Fab" user)
		(33 "B.Fab" user)
	)
	(footprint "antmicro-footprints:C_0402_1005Metric"
		(layer "F.Cu")
		(at 232.8 145.4 -90)
		(descr "Capacitor SMD 0402")
		(tags "capacitor SMD 0402")
		(property "Reference" "C243"
			(at -1.15 0.4 0)
			(layer "F.SilkS")
			(effects
				(font
					(size 0.7 0.7)
					(thickness 0.15)
				)
				(justify right bottom)
			)
		)
		(property "Value" "C_1u_0402"
			(at 0 1.4 90)
			(layer "F.Fab")
			(effects
				(font
					(size 0.7 0.7)
					(thickness 0.15)
				)
				(justify right bottom)
			)
		)
		(property "Description" "SMD Multilayer Ceramic Capacitor, 1 µF, 10 V, 0402 [1005 Metric], ± 10%, X6S, C"
			(at 0 0 270)
			(layer "F.Fab")
			(hide yes)
			(effects
				(font
					(size 1.27 1.27)
					(thickness 0.15)
				)
			)
		)
		(property "Author" "Antmicro"
			(at 87.4 378.2 0)
			(layer "F.Fab")
			(hide yes)
			(effects
				(font
					(size 1 1)
					(thickness 0.15)
				)
			)
		)
		(property "Dielectric" ""
			(at 87.4 378.2 0)
			(layer "F.Fab")
			(hide yes)
			(effects
				(font
					(size 1 1)
					(thickness 0.15)
				)
			)
		)
		(property "License" "Apache-2.0"
			(at 87.4 378.2 0)
			(layer "F.Fab")
			(hide yes)
			(effects
				(font
					(size 1 1)
					(thickness 0.15)
				)
			)
		)
		(property "MPN" "C1005X6S1A105K050BC"
			(at 87.4 378.2 0)
			(layer "F.Fab")
			(hide yes)
			(effects
				(font
					(size 1 1)
					(thickness 0.15)
				)
			)
		)
		(property "Manufacturer" "TDK"
			(at 87.4 378.2 0)
			(layer "F.Fab")
			(hide yes)
			(effects
				(font
					(size 1 1)
					(thickness 0.15)
				)
			)
		)
		(property "Val" "1u"
			(at 87.4 378.2 0)
			(layer "F.Fab")
			(hide yes)
			(effects
				(font
					(size 1 1)
					(thickness 0.15)
				)
			)
		)
		(property "Voltage" ""
			(at 87.4 378.2 0)
			(layer "F.Fab")
			(hide yes)
			(effects
				(font
					(size 1 1)
					(thickness 0.15)
				)
			)
		)
		(sheetname "USB PHY")
		(sheetfile "usb-phy.kicad_sch")
		(attr smd)
		(fp_rect
			(start -0.925 -0.47)
			(end 0.925 0.47)
			(stroke
				(width 0.05)
				(type default)
			)
			(fill no)
			(layer "F.CrtYd")
		)
		(fp_line
			(start -0.494 0.248)
			(end -0.494 -0.25)
			(stroke
				(width 0.15)
				(type solid)
			)
			(layer "F.Fab")
		)
		(fp_line
			(start 0.504 0.248)
			(end -0.494 0.248)
			(stroke
				(width 0.15)
				(type solid)
			)
			(layer "F.Fab")
		)
		(fp_line
			(start -0.494 -0.25)
			(end 0.504 -0.25)
			(stroke
				(width 0.15)
				(type solid)
			)
			(layer "F.Fab")
		)
		(fp_line
			(start 0.504 -0.25)
			(end 0.504 0.248)
			(stroke
				(width 0.15)
				(type solid)
			)
			(layer "F.Fab")
		)
		(pad "1" smd roundrect
			(at -0.48 0 270)
			(size 0.59 0.64)
			(layers "F.Cu" "F.Mask" "F.Paste")
			(roundrect_rratio 0.25)
			(net 1 "GND")
			(pintype "passive")
		)
		(pad "2" smd roundrect
			(at 0.48 0 270)
			(size 0.59 0.64)
			(layers "F.Cu" "F.Mask" "F.Paste")
			(roundrect_rratio 0.25)
			(net 24 "+3V3")
			(pintype "passive")
		)
	)
	(footprint "antmicro-footprints:R_0402_1005Metric"
		(layer "F.Cu")
		(at 243.099 113.904 180)
		(descr "Resistor SMD 0402")
		(tags "resistor SMD 0402")
		(property "Reference" "R347"
			(at 1.449 1.704 0)
			(layer "F.SilkS")
			(effects
				(font
					(size 0.7 0.7)
					(thickness 0.15)
				)
				(justify left bottom)
			)
		)
		(property "Value" "R_0R_0402"
			(at 0 1.4 180)
			(layer "F.Fab")
			(effects
				(font
					(size 0.7 0.7)
					(thickness 0.15)
				)
				(justify left bottom)
			)
		)
		(property "Description" "SMD Chip Resistor, Jumper, 0 ohm, 100 mW, 0402 [1005 Metric], Thick Film, General Purpose"
			(at 0 0 180)
			(layer "F.Fab")
			(hide yes)
			(effects
				(font
					(size 1.27 1.27)
					(thickness 0.15)
				)
			)
		)
		(property "Author" "Antmicro"
			(at 486.198 227.808 0)
			(layer "F.Fab")
			(hide yes)
			(effects
				(font
					(size 1 1)
					(thickness 0.15)
				)
			)
		)
		(property "Current" "1A"
			(at 486.198 227.808 0)
			(layer "F.Fab")
			(hide yes)
			(effects
				(font
					(size 1 1)
					(thickness 0.15)
				)
			)
		)
		(property "DNP" "DNP"
			(at 486.198 227.808 0)
			(layer "F.Fab")
			(hide yes)
			(effects
				(font
					(size 1 1)
					(thickness 0.15)
				)
			)
		)
		(property "License" "Apache-2.0"
			(at 486.198 227.808 0)
			(layer "F.Fab")
			(hide yes)
			(effects
				(font
					(size 1 1)
					(thickness 0.15)
				)
			)
		)
		(property "MPN" "ERJ2GE0R00X"
			(at 486.198 227.808 0)
			(layer "F.Fab")
			(hide yes)
			(effects
				(font
					(size 1 1)
					(thickness 0.15)
				)
			)
		)
		(property "Manufacturer" "Panasonic"
			(at 486.198 227.808 0)
			(layer "F.Fab")
			(hide yes)
			(effects
				(font
					(size 1 1)
					(thickness 0.15)
				)
			)
		)
		(property "Tolerance" ""
			(at 486.198 227.808 0)
			(layer "F.Fab")
			(hide yes)
			(effects
				(font
					(size 1 1)
					(thickness 0.15)
				)
			)
		)
		(property "Val" "0R"
			(at 486.198 227.808 0)
			(layer "F.Fab")
			(hide yes)
			(effects
				(font
					(size 1 1)
					(thickness 0.15)
				)
			)
		)
		(property "dnp" ""
			(at 486.198 227.808 0)
			(layer "F.Fab")
			(hide yes)
			(effects
				(font
					(size 1 1)
					(thickness 0.15)
				)
			)
		)
		(property "exclude_from_bom" ""
			(at 486.198 227.808 0)
			(layer "F.Fab")
			(hide yes)
			(effects
				(font
					(size 1 1)
					(thickness 0.15)
				)
			)
		)
		(sheetname "USB PHY")
		(sheetfile "usb-phy.kicad_sch")
		(attr smd exclude_from_bom)
		(fp_rect
			(start -0.925 -0.47)
			(end 0.925 0.47)
			(stroke
				(width 0.05)
				(type default)
			)
			(fill no)
			(layer "F.CrtYd")
		)
		(fp_rect
			(start -0.5 -0.25)
			(end 0.5 0.25)
			(stroke
				(width 0.15)
				(type solid)
			)
			(fill no)
			(layer "F.Fab")
		)
		(pad "1" smd roundrect
			(at -0.48 0 180)
			(size 0.59 0.64)
			(layers "F.Cu" "F.Mask" "F.Paste")
			(roundrect_rratio 0.25)
			(net 703 "+5V")
			(pintype "passive")
		)
		(pad "2" smd roundrect
			(at 0.48 0 180)
			(size 0.59 0.64)
			(layers "F.Cu" "F.Mask" "F.Paste")
			(roundrect_rratio 0.25)
			(net 385 "Net-(U43-EN)")
			(pintype "passive")
		)
	)
	(footprint "antmicro-footprints:R_0402_1005Metric"
		(layer "F.Cu")
		(at 225.025 120.5)
		(descr "Resistor SMD 0402")
		(tags "resistor SMD 0402")
		(property "Reference" "R66"
			(at -2.975 0.4 0)
			(layer "F.SilkS")
			(effects
				(font
					(size 0.7 0.7)
					(thickness 0.15)
				)
				(justify left bottom)
			)
		)
		(property "Value" "R_10k_0402"
			(at 0 1.4 0)
			(layer "F.Fab")
			(effects
				(font
					(size 0.7 0.7)
					(thickness 0.15)
				)
				(justify left bottom)
			)
		)
		(property "Description" "SMD Chip Resistor, 10 kohm, ± 1%, 62.5 mW, 0402 [1005 Metric], Thick Film, General Purpose"
			(at 0 0 0)
			(layer "F.Fab")
			(hide yes)
			(effects
				(font
					(size 1.27 1.27)
					(thickness 0.15)
				)
			)
		)
		(property "Author" "Antmicro"
			(at 0 0 0)
			(layer "F.Fab")
			(hide yes)
			(effects
				(font
					(size 1 1)
					(thickness 0.15)
				)
			)
		)
		(property "License" "Apache-2.0"
			(at 0 0 0)
			(layer "F.Fab")
			(hide yes)
			(effects
				(font
					(size 1 1)
					(thickness 0.15)
				)
			)
		)
		(property "MPN" "CR0402-FX-1002GLF"
			(at 0 0 0)
			(layer "F.Fab")
			(hide yes)
			(effects
				(font
					(size 1 1)
					(thickness 0.15)
				)
			)
		)
		(property "Manufacturer" "Bourns"
			(at 0 0 0)
			(layer "F.Fab")
			(hide yes)
			(effects
				(font
					(size 1 1)
					(thickness 0.15)
				)
			)
		)
		(property "Tolerance" "1%"
			(at 0 0 0)
			(layer "F.Fab")
			(hide yes)
			(effects
				(font
					(size 1 1)
					(thickness 0.15)
				)
			)
		)
		(property "Val" "10k"
			(at 0 0 0)
			(layer "F.Fab")
			(hide yes)
			(effects
				(font
					(size 1 1)
					(thickness 0.15)
				)
			)
		)
		(sheetname "SPI Flash + SD Card")
		(sheetfile "spi-flash.kicad_sch")
		(attr smd)
		(fp_rect
			(start -0.925 -0.47)
			(end 0.925 0.47)
			(stroke
				(width 0.05)
				(type default)
			)
			(fill no)
			(layer "F.CrtYd")
		)
		(fp_rect
			(start -0.5 -0.25)
			(end 0.5 0.25)
			(stroke
				(width 0.15)
				(type solid)
			)
			(fill no)
			(layer "F.Fab")
		)
		(pad "1" smd roundrect
			(at -0.48 0)
			(size 0.59 0.64)
			(layers "F.Cu" "F.Mask" "F.Paste")
			(roundrect_rratio 0.25)
			(net 403 "/FPGA Bank 14 & 15/SYSTEM_FLASH.DQ2")
			(pintype "passive")
		)
		(pad "2" smd roundrect
			(at 0.48 0)
			(size 0.59 0.64)
			(layers "F.Cu" "F.Mask" "F.Paste")
			(roundrect_rratio 0.25)
			(net 24 "+3V3")
			(pintype "passive")
		)
	)
	(footprint "antmicro-footprints:SW_KMR211NGLFS_SMD"
		(layer "F.Cu")
		(at 266.8 93.2 180)
		(property "Reference" "S5"
			(at 0.7 -2.6 180)
			(layer "F.SilkS")
			(effects
				(font
					(size 0.7 0.7)
					(thickness 0.15)
				)
				(justify left bottom)
			)
		)
		(property "Value" "SW_KMR211NGLFS_SMD"
			(at -3 3 180)
			(layer "F.Fab")
			(effects
				(font
					(size 0.7 0.7)
					(thickness 0.15)
				)
				(justify left bottom)
			)
		)
		(property "Description" "Tactile Switch, KMR 2 Series, Top Actuated, Surface Mount, Oval Button, 120 gf, 50mA at 32VDC"
			(at 0 0 180)
			(layer "F.Fab")
			(hide yes)
			(effects
				(font
					(size 1.27 1.27)
					(thickness 0.15)
				)
			)
		)
		(property "Author" "Antmicro"
			(at 533.6 186.4 0)
			(layer "F.Fab")
			(hide yes)
			(effects
				(font
					(size 1 1)
					(thickness 0.15)
				)
			)
		)
		(property "License" "Apache-2.0"
			(at 533.6 186.4 0)
			(layer "F.Fab")
			(hide yes)
			(effects
				(font
					(size 1 1)
					(thickness 0.15)
				)
			)
		)
		(property "MPN" "KMR211NGLFS"
			(at 533.6 186.4 0)
			(layer "F.Fab")
			(hide yes)
			(effects
				(font
					(size 1 1)
					(thickness 0.15)
				)
			)
		)
		(property "Manufacturer" "C&K"
			(at 533.6 186.4 0)
			(layer "F.Fab")
			(hide yes)
			(effects
				(font
					(size 1 1)
					(thickness 0.15)
				)
			)
		)
		(sheetname "User GPIO + LED + button + DIP switch")
		(sheetfile "user-gpio.kicad_sch")
		(attr smd)
		(fp_line
			(start 2.101 1.601)
			(end 2.101 1.48)
			(stroke
				(width 0.15)
				(type solid)
			)
			(layer "F.SilkS")
		)
		(fp_line
			(start 2.101 1.601)
			(end -2.1 1.601)
			(stroke
				(width 0.15)
				(type solid)
			)
			(layer "F.SilkS")
		)
		(fp_line
			(start 2.101 -1.58)
			(end 2.101 -1.459)
			(stroke
				(width 0.15)
				(type solid)
			)
			(layer "F.SilkS")
		)
		(fp_line
			(start 2.101 -1.6)
			(end -2.1 -1.6)
			(stroke
				(width 0.15)
				(type solid)
			)
			(layer "F.SilkS")
		)
		(fp_line
			(start -2.1 1.601)
			(end -2.1 1.48)
			(stroke
				(width 0.15)
				(type solid)
			)
			(layer "F.SilkS")
		)
		(fp_line
			(start -2.1 -1.6)
			(end -2.1 -1.499)
			(stroke
				(width 0.15)
				(type solid)
			)
			(layer "F.SilkS")
		)
		(fp_rect
			(start 2.751 1.75)
			(end -2.748 -1.749)
			(stroke
				(width 0.05)
				(type solid)
			)
			(fill no)
			(layer "F.CrtYd")
		)
		(fp_line
			(start 2.101 1.601)
			(end 2.101 -1.6)
			(stroke
				(width 0.15)
				(type solid)
			)
			(layer "F.Fab")
		)
		(fp_line
			(start 2.101 -1.6)
			(end -2.1 -1.6)
			(stroke
				(width 0.15)
				(type solid)
			)
			(layer "F.Fab")
		)
		(fp_line
			(start 0.25 0.802)
			(end -0.248 0.802)
			(stroke
				(width 0.15)
				(type solid)
			)
			(layer "F.Fab")
		)
		(fp_line
			(start -0.248 -0.8)
			(end 0.25 -0.8)
			(stroke
				(width 0.15)
				(type solid)
			)
			(layer "F.Fab")
		)
		(fp_line
			(start -2.1 1.601)
			(end 2.101 1.601)
			(stroke
				(width 0.15)
				(type solid)
			)
			(layer "F.Fab")
		)
		(fp_line
			(start -2.1 -1.6)
			(end -2.1 1.601)
			(stroke
				(width 0.15)
				(type solid)
			)
			(layer "F.Fab")
		)
		(fp_arc
			(start 0.25 -0.8)
			(mid 1.051001 0.001)
			(end 0.25 0.802)
			(stroke
				(width 0.15)
				(type solid)
			)
			(layer "F.Fab")
		)
		(fp_arc
			(start -0.248 0.802)
			(mid -1.050001 0.001)
			(end -0.248 -0.8)
			(stroke
				(width 0.15)
				(type solid)
			)
			(layer "F.Fab")
		)
		(pad "1" smd rect
			(at -2.048 -0.8)
			(size 0.9 1)
			(layers "F.Cu" "F.Mask" "F.Paste")
			(net 1232 "/USER_IO.BUTTON3")
			(pinfunction "1")
			(pintype "passive")
		)
		(pad "2" smd rect
			(at 2.05 -0.8)
			(size 0.9 1)
			(layers "F.Cu" "F.Mask" "F.Paste")
			(net 1232 "/USER_IO.BUTTON3")
			(pinfunction "2")
			(pintype "passive")
		)
		(pad "3" smd rect
			(at -2.048 0.802)
			(size 0.9 1)
			(layers "F.Cu" "F.Mask" "F.Paste")
			(net 1 "GND")
			(pinfunction "3")
			(pintype "passive")
		)
		(pad "4" smd rect
			(at 2.05 0.802)
			(size 0.9 1)
			(layers "F.Cu" "F.Mask" "F.Paste")
			(net 1 "GND")
			(pinfunction "4")
			(pintype "passive")
		)
	)
	(footprint "antmicro-footprints:NetTie-2_SMD_Pad0.127mm"
		(layer "F.Cu")
		(at 252.1 143.502 -90)
		(descr "Net tie, 2 pin, 0.127mm  SMD pads")
		(tags "net tie")
		(property "Reference" "NT14"
			(at -0.128 -1.345 270)
			(layer "F.SilkS")
			(hide yes)
			(effects
				(font
					(size 0.7 0.7)
					(thickness 0.15)
				)
				(justify left bottom)
			)
		)
		(property "Value" "Net-Tie_2"
			(at 0 1.199 270)
			(layer "F.Fab")
			(effects
				(font
					(size 0.7 0.7)
					(thickness 0.15)
				)
				(justify left bottom)
			)
		)
		(property "Description" "Net tie, 2 pins"
			(at 0 0 270)
			(layer "F.Fab")
			(hide yes)
			(effects
				(font
					(size 1.27 1.27)
					(thickness 0.15)
				)
			)
		)
		(property "Author" "Antmicro"
			(at 108.598 395.602 0)
			(layer "F.Fab")
			(hide yes)
			(effects
				(font
					(size 1 1)
					(thickness 0.15)
				)
			)
		)
		(property "License" "Apache-2.0"
			(at 108.598 395.602 0)
			(layer "F.Fab")
			(hide yes)
			(effects
				(font
					(size 1 1)
					(thickness 0.15)
				)
			)
		)
		(property "MPN" ""
			(at 108.598 395.602 0)
			(layer "F.Fab")
			(hide yes)
			(effects
				(font
					(size 1 1)
					(thickness 0.15)
				)
			)
		)
		(property "Manufacturer" ""
			(at 108.598 395.602 0)
			(layer "F.Fab")
			(hide yes)
			(effects
				(font
					(size 1 1)
					(thickness 0.15)
				)
			)
		)
		(sheetname "FPGA Bank 14 & 15")
		(sheetfile "fpga-bank-14-15.kicad_sch")
		(attr exclude_from_pos_files)
		(net_tie_pad_groups "1, 2")
		(fp_poly
			(pts
				(xy -0.0635 -0.0635) (xy 0.0625 -0.0635) (xy 0.0625 0.0635) (xy -0.0635 0.0635)
			)
			(stroke
				(width 0)
				(type solid)
			)
			(fill yes)
			(layer "F.Cu")
		)
		(pad "1" smd roundrect
			(at -0.127 0 90)
			(size 0.127 0.127)
			(layers "F.Cu")
			(roundrect_rratio 0.5)
			(chamfer_ratio 0)
			(chamfer top_left bottom_left)
			(net 43 "/FPGA Bank 14 & 15/SYSTEM_FLASH.DQ1")
			(pinfunction "1")
			(pintype "passive")
		)
		(pad "2" smd roundrect
			(at 0.126 0 270)
			(size 0.127 0.127)
			(layers "F.Cu")
			(roundrect_rratio 0.5)
			(chamfer_ratio 0)
			(chamfer top_left bottom_left)
			(net 1327 "/SUP_MCU.FPGA_MOSI")
			(pinfunction "2")
			(pintype "passive")
		)
	)
)
